# TIMECARD (Time Appliance Project (Time Card)) — schematic netlist excerpt (pin names and nets, part order shuffled) for the footprints in the layout excerpt that follows; sources: Cadence DE-HDL packaged netlist, KiCad conversion of R4006-B0001-02_R01.brd

R262  RESISTOR  1KOHM 1%  pkg SMC_0402R_H016  page 26 : \1\ = UNNAMED_14_RESISTOR_I65_2 ; \2\ = XP12R0V
C80  CAPACITOR  0.1UF 10V 10%  pkg SMC_0402R_H022  page 22 : \1\ = XP3R3V_GPS ; \2\ = SG

(kicad_pcb
	(version 20260206)
	(generator "pcbnew")
	(generator_version "10.0")
	(general
		(thickness 1.6)
		(legacy_teardrops no)
	)
	(paper "A4")
	(title_block
		(title "timecard-production-celestica-r4006 — R4006-B0001-02_R01.brd")
		(comment 1 "Time Appliance Project (Time Card) / footprints 785-786 of 1113")
	)
	(layers
		(0 "F.Cu" signal "TOP")
		(4 "In1.Cu" signal "L02_GND1")
		(6 "In2.Cu" signal "L03_SIG1")
		(8 "In3.Cu" signal "L04_GND2")
		(10 "In4.Cu" signal "L05_VCC1")
		(12 "In5.Cu" signal "L06_VCC2")
		(14 "In6.Cu" signal "L07_GND3")
		(16 "In7.Cu" signal "L08_SIG2")
		(18 "In8.Cu" signal "L09_GND4")
		(2 "B.Cu" signal "BOTTOM")
		(9 "F.Adhes" user "F.Adhesive")
		(11 "B.Adhes" user "B.Adhesive")
		(13 "F.Paste" user "Package Geometry/Pastemask Top")
		(15 "B.Paste" user "Package Geometry/Pastemask Bottom")
		(5 "F.SilkS" user "Ref Des/Silkscreen Top")
		(7 "B.SilkS" user "Ref Des/Silkscreen Bottom")
		(1 "F.Mask" user "Board Geometry/Soldermask Top")
		(3 "B.Mask" user "Board Geometry/Soldermask Bottom")
		(17 "Dwgs.User" user "User.Drawings")
		(19 "Cmts.User" user "User.Comments")
		(21 "Eco1.User" user "User.Eco1")
		(23 "Eco2.User" user "User.Eco2")
		(25 "Edge.Cuts" user "Board Geometry/Outline")
		(27 "Margin" user)
		(31 "F.CrtYd" user "Package Geometry/Place Bound Top")
		(29 "B.CrtYd" user "Package Geometry/Place Bound Bottom")
		(35 "F.Fab" user "Ref Des/Assembly Top")
		(33 "B.Fab" user "Ref Des/Assembly Bottom")
	)
	(footprint ""
		(layer "B.Cu")
		(at 117.729 -98.933)
		(property "Reference" "C80"
			(at -1.016 1.30937 0)
			(unlocked yes)
			(layer "B.SilkS")
			(effects
				(font
					(size 0.7874 0.5842)
					(thickness 0.1524)
				)
				(justify mirror)
			)
		)
		(property "Value" "VAL*"
			(at -0.0762 2.067306 0)
			(unlocked yes)
			(layer "B.Fab")
			(hide yes)
			(effects
				(font
					(size 0.7874 0.5842)
					(thickness 0.1524)
				)
				(justify mirror)
			)
		)
		(property "Tolerance" "TOL*"
			(at -0.0762 3.032506 0)
			(unlocked yes)
			(layer "Cmts.User")
			(hide yes)
			(effects
				(font
					(size 0.7874 0.5842)
					(thickness 0.1524)
				)
				(justify mirror)
			)
		)
		(property "User Part Number" "PARTNUM*"
			(at -0.1016 4.023106 0)
			(unlocked yes)
			(layer "Cmts.User")
			(hide yes)
			(effects
				(font
					(size 0.7874 0.5842)
					(thickness 0.1524)
				)
				(justify mirror)
			)
		)
		(property "Device Type" "CAPACITOR-G105-0B104-CK,0.1UF,A"
			(at -0.0508 1.127506 0)
			(unlocked yes)
			(layer "B.Fab")
			(hide yes)
			(effects
				(font
					(size 0.7874 0.5842)
					(thickness 0.1524)
				)
				(justify mirror)
			)
		)
		(duplicate_pad_numbers_are_jumpers no)
		(fp_line
			(start -1.143 -0.5588)
			(end 1.143 -0.5588)
			(stroke
				(width 0.1)
				(type default)
			)
			(layer "B.SilkS")
		)
		(fp_line
			(start -1.143 0.5588)
			(end -1.143 -0.5588)
			(stroke
				(width 0.1)
				(type default)
			)
			(layer "B.SilkS")
		)
		(fp_line
			(start 1.143 -0.5588)
			(end 1.143 0.5588)
			(stroke
				(width 0.1)
				(type default)
			)
			(layer "B.SilkS")
		)
		(fp_line
			(start 1.143 0.5588)
			(end -1.143 0.5588)
			(stroke
				(width 0.1)
				(type default)
			)
			(layer "B.SilkS")
		)
		(fp_rect
			(start -1.143 -0.5588)
			(end 1.143 0.5588)
			(stroke
				(width 0)
				(type default)
			)
			(fill no)
			(layer "B.CrtYd")
		)
		(fp_line
			(start -0.508 -0.3048)
			(end 0.508 -0.3048)
			(stroke
				(width 0.1)
				(type default)
			)
			(layer "B.Fab")
		)
		(fp_line
			(start -0.508 0.3048)
			(end -0.508 -0.3048)
			(stroke
				(width 0.1)
				(type default)
			)
			(layer "B.Fab")
		)
		(fp_line
			(start 0.508 -0.3048)
			(end 0.508 0.3048)
			(stroke
				(width 0.1)
				(type default)
			)
			(layer "B.Fab")
		)
		(fp_line
			(start 0.508 0.3048)
			(end -0.508 0.3048)
			(stroke
				(width 0.1)
				(type default)
			)
			(layer "B.Fab")
		)
		(pad "1" smd rect
			(at 0.5334 0 180)
			(size 0.7112 0.6096)
			(layers "B.Cu" "B.Mask" "B.Paste")
			(net "XP3R3V_GPS")
		)
		(pad "2" smd rect
			(at -0.5334 0 180)
			(size 0.7112 0.6096)
			(layers "B.Cu" "B.Mask" "B.Paste")
			(net "SG")
		)
		(zone
			(layer "B.Cu")
			(hatch none 0.5)
			(connect_pads
				(clearance 0)
			)
			(min_thickness 0.25)
			(keepout
				(tracks allowed)
				(vias not_allowed)
				(pads allowed)
				(copperpour not_allowed)
				(footprints allowed)
			)
			(placement
				(enabled no)
				(sheetname "")
			)
			(fill
				(thermal_gap 0.5)
				(thermal_bridge_width 0.5)
				(island_removal_mode 0)
			)
			(polygon
				(pts
					(xy 117.6528 -99.2378) (xy 117.6528 -98.6282) (xy 117.8052 -98.6282) (xy 117.8052 -99.2378)
				)
			)
		)
	)
	(footprint ""
		(layer "B.Cu")
		(at 147.066 -103.505)
		(property "Reference" "R262"
			(at 1.016 3.08737 0)
			(unlocked yes)
			(layer "B.SilkS")
			(effects
				(font
					(size 0.7874 0.5842)
					(thickness 0.1524)
				)
				(justify mirror)
			)
		)
		(property "Value" "VAL*"
			(at -0.02032 2.13233 0)
			(unlocked yes)
			(layer "B.Fab")
			(hide yes)
			(effects
				(font
					(size 0.7874 0.5842)
					(thickness 0.1524)
				)
				(justify mirror)
			)
		)
		(property "Tolerance" "TOL*"
			(at -0.044704 3.05435 0)
			(unlocked yes)
			(layer "Cmts.User")
			(hide yes)
			(effects
				(font
					(size 0.7874 0.5842)
					(thickness 0.1524)
				)
				(justify mirror)
			)
		)
		(property "User Part Number" "PARTNUM*"
			(at -0.02032 4.024884 0)
			(unlocked yes)
			(layer "Cmts.User")
			(hide yes)
			(effects
				(font
					(size 0.7874 0.5842)
					(thickness 0.1524)
				)
				(justify mirror)
			)
		)
		(property "Device Type" "RESISTOR-G155-11001-01,1KOHM,1%"
			(at -0.008382 1.210564 0)
			(unlocked yes)
			(layer "B.Fab")
			(hide yes)
			(effects
				(font
					(size 0.7874 0.5842)
					(thickness 0.1524)
				)
				(justify mirror)
			)
		)
		(duplicate_pad_numbers_are_jumpers no)
		(fp_line
			(start -1.143 -0.5588)
			(end 1.143 -0.5588)
			(stroke
				(width 0.1)
				(type default)
			)
			(layer "B.SilkS")
		)
		(fp_line
			(start -1.143 0.5588)
			(end -1.143 -0.5588)
			(stroke
				(width 0.1)
				(type default)
			)
			(layer "B.SilkS")
		)
		(fp_line
			(start 1.143 -0.5588)
			(end 1.143 0.5588)
			(stroke
				(width 0.1)
				(type default)
			)
			(layer "B.SilkS")
		)
		(fp_line
			(start 1.143 0.5588)
			(end -1.143 0.5588)
			(stroke
				(width 0.1)
				(type default)
			)
			(layer "B.SilkS")
		)
		(fp_rect
			(start 1.143 0.5588)
			(end -1.143 -0.5588)
			(stroke
				(width 0)
				(type default)
			)
			(fill no)
			(layer "B.CrtYd")
		)
		(fp_line
			(start -0.508 -0.3048)
			(end 0.508 -0.3048)
			(stroke
				(width 0.1)
				(type default)
			)
			(layer "B.Fab")
		)
		(fp_line
			(start -0.508 0.3048)
			(end -0.508 -0.3048)
			(stroke
				(width 0.1)
				(type default)
			)
			(layer "B.Fab")
		)
		(fp_line
			(start 0.508 -0.3048)
			(end 0.508 0.3048)
			(stroke
				(width 0.1)
				(type default)
			)
			(layer "B.Fab")
		)
		(fp_line
			(start 0.508 0.3048)
			(end -0.508 0.3048)
			(stroke
				(width 0.1)
				(type default)
			)
			(layer "B.Fab")
		)
		(pad "1" smd rect
			(at 0.5334 0 180)
			(size 0.7112 0.6096)
			(layers "B.Cu" "B.Mask" "B.Paste")
			(net "UNNAMED_14_RESISTOR_I65_2")
		)
		(pad "2" smd rect
			(at -0.5334 0 180)
			(size 0.7112 0.6096)
			(layers "B.Cu" "B.Mask" "B.Paste")
			(net "XP12R0V")
		)
		(zone
			(layer "B.Cu")
			(hatch none 0.5)
			(connect_pads
				(clearance 0)
			)
			(min_thickness 0.25)
			(keepout
				(tracks allowed)
				(vias not_allowed)
				(pads allowed)
				(copperpour not_allowed)
				(footprints allowed)
			)
			(placement
				(enabled no)
				(sheetname "")
			)
			(fill
				(thermal_gap 0.5)
				(thermal_bridge_width 0.5)
				(island_removal_mode 0)
			)
			(polygon
				(pts
					(xy 147.1422 -103.2002) (xy 147.1422 -103.8098) (xy 146.9898 -103.8098) (xy 146.9898 -103.2002)
				)
			)
		)
	)
)
